FILE_TYPE = CONNECTIVITY;
{Allegro Design Entry HDL 16.6-p007 (v16-6-112F) 10/10/2012}
"PAGE_NUMBER" = 39;
0"NC";
1"PVCCMCP_CPU0\g";
2"PVCCMCP_CPU0\g";
3"PVCCMCP_CPU0\g";
4"PVCCIO_CPU0\g";
5"VSENSE_PVCCMCP_CPU0_SKT_VSEN";
6"VSENSE_PVCCMCP_CPU0_SKT_VRTN";
7"VSENSE_PVCCIOMCP_CPU0_SKT_VSEN";
8"VSENSE_PVCCIOMCP_CPU0_SKT_VRTN";
9"TP_CPU0_RSVD_61";
10"TP_CPU0_KTI2_DFX_DN";
11"TP_CPU0_RSVD_64";
12"TP_CPU0_RSVD_66";
13"TP_CPU0_RSVD_67";
14"TP_CPU0_RSVD_69";
15"TP_CPU0_RSVD_70";
16"TP_CPU0_RSVD_72";
17"TP_CPU0_RSVD_73";
18"PD_CPU0_MCP01_DMON";
19"VSENSE_PVCCIO_CPU0_SKT_VRTN";
20"TP_CPU0_KTI2_AMONV";
21"VSENSE_PVSA_CPU0_SKT_VSEN";
22"VSENSE_PVSA_CPU0_SKT_VRTN";
23"VSENSE_PVCCIO_CPU0_SKT_VSEN";
24"TP_CPU0_RSVD_0";
25"TP_CPU0_RSVD_1";
26"TP_CPU0_RSVD_2";
27"TP_CPU0_RSVD_3";
28"TP_CPU0_RSVD_4";
29"TP_CPU0_RSVD_5";
30"TP_CPU0_RSVD_6";
31"TP_CPU0_RSVD_7";
32"TP_CPU0_RSVD_8";
33"TP_CPU0_RSVD_9";
34"TP_CPU0_RSVD_10";
35"TP_CPU0_RSVD_11";
36"TP_CPU0_RSVD_12";
37"TP_CPU0_RSVD_13";
38"TP_CPU0_RSVD_14";
39"TP_CPU0_RSVD_15";
40"TP_CPU0_RSVD_16";
41"TP_CPU0_RSVD_17";
42"TP_CPU0_RSVD_18";
43"TP_CPU0_RSVD_19";
44"TP_CPU0_RSVD_20";
45"TP_CPU0_RSVD_21";
46"TP_CPU0_RSVD_22";
47"TP_CPU0_RSVD_23";
48"TP_CPU0_RSVD_24";
49"TP_CPU0_RSVD_25";
50"TP_CPU0_RSVD_26";
51"TP_CPU0_RSVD_27";
52"TP_CPU0_RSVD_28";
53"TP_CPU0_RSVD_29";
54"TP_CPU0_RSVD_30";
55"TP_CPU0_RSVD_31";
56"TP_CPU0_RSVD_32";
57"TP_CPU0_RSVD_33";
58"TP_CPU0_RSVD_34";
59"TP_CPU0_RSVD_35";
60"TP_CPU0_RSVD_36";
61"TP_CPU0_RSVD_37";
62"TP_CPU0_RSVD_38";
63"TP_CPU0_RSVD_39";
64"TP_CPU0_RSVD_40";
65"TP_CPU0_RSVD_41";
66"TP_CPU0_RSVD_42";
67"TP_CPU0_RSVD_43";
68"TP_CPU0_RSVD_44";
69"TP_CPU0_RSVD_45";
70"TP_CPU0_RSVD_46";
71"TP_CPU0_RSVD_47";
72"TP_CPU0_RSVD_48";
73"TP_CPU0_RSVD_49";
74"TP_CPU0_RSVD_50";
75"TP_CPU0_RSVD_51";
76"TP_CPU0_RSVD_53";
77"TP_CPU0_RSVD_54";
78"TP_CPU0_RSVD_55";
79"TP_CPU0_RSVD_56";
80"TP_CPU0_RSVD_57";
81"TP_CPU0_RSVD_59";
82"TP_CPU0_RSVD_60";
%"VCC_CORE"
"1","(-2250,4025)","0","mstr_symbols","I123";
;
CDS_LIB"mstr_symbols"
HDL_POWER"PVCCMCP_CPU0";
"A"1;
%"VCC_CORE"
"1","(-6025,2875)","0","mstr_symbols","I125";
;
CDS_LIB"mstr_symbols"
HDL_POWER"PVCCMCP_CPU0";
"A"2;
%"VCC_CORE"
"1","(-6825,1950)","0","mstr_symbols","I126";
;
CDS_LIB"mstr_symbols"
HDL_POWER"PVCCMCP_CPU0";
"A"3;
%"SKX_EXT_B"
"22","(-4250,2550)","0","chpset_lib","I127";
;
CDS_SEC"22"
ROOM"CPU0"
CDS_LOCATION"U5D1"
SEC"22"
CDS_LIB"chpset_lib"
SEC_TYPE"BGA1"
PACK_TYPE"BGA1"
MATERIAL"IC"
PART_NUMBER"TBD"
LOCATION"U5D1";
"VSS_VCCSA_SENSE"
$PN"CG76"22;
"VSS_VCCIO_SENSE"
$PN"BF5"19;
"VCCSA_SENSE"
$PN"CE76"21;
"VCCIO_SENSE"
$PN"BH5"23;
"VCCIO<0>"
$PN"EE10"4;
"VCCIO<1>"
$PN"AE10"4;
"VCCIO<2>"
$PN"AF5"4;
"VCCIO<3>"
$PN"DV11"4;
"VCCIO<4>"
$PN"AM5"4;
"VCCIO<5>"
$PN"AT5"4;
"VCCIO<6>"
$PN"AT7"4;
"VCCIO<7>"
$PN"BE24"4;
"VCCIO<8>"
$PN"DK21"4;
"VCCIO<9>"
$PN"CF5"4;
"VCCIO<10>"
$PN"CG14"4;
"VCCIO<11>"
$PN"CL20"4;
"VCCIO<12>"
$PN"CP13"4;
"VCCIO<13>"
$PN"DE14"4;
"VCCIO<14>"
$PN"DC18"4;
"VCCIO<15>"
$PN"CY17"4;
"VCCIO<16>"
$PN"CU18"4;
"VCCIO<17>"
$PN"CV21"4;
"VCCIO<18>"
$PN"CU12"4;
"VCCIO<19>"
$PN"CN6"4;
"RSVD<0>"
$PN"EF83"24;
"RSVD<1>"
$PN"EF81"25;
"RSVD<2>"
$PN"EF77"26;
"RSVD<3>"
$PN"EF47"27;
"RSVD<4>"
$PN"EE84"28;
"RSVD<5>"
$PN"EE82"29;
"RSVD<6>"
$PN"EE6"30;
"RSVD<7>"
$PN"EE46"31;
"RSVD<8>"
$PN"EE16"32;
"RSVD<9>"
$PN"ED83"33;
"RSVD<10>"
$PN"ED5"34;
"RSVD<11>"
$PN"ED45"35;
"RSVD<12>"
$PN"EC84"36;
"RSVD<13>"
$PN"EC44"37;
"RSVD<14>"
$PN"EC4"38;
"RSVD<15>"
$PN"EC16"39;
"RSVD<16>"
$PN"EB85"40;
"RSVD<17>"
$PN"EB5"41;
"RSVD<18>"
$PN"EB3"42;
"RSVD<19>"
$PN"EA44"43;
"RSVD<20>"
$PN"EA4"44;
"RSVD<21>"
$PN"DY3"45;
"RSVD<22>"
$PN"DW46"46;
"RSVD<23>"
$PN"DW44"47;
"RSVD<24>"
$PN"DV71"48;
"RSVD<25>"
$PN"DV61"49;
"RSVD<26>"
$PN"DU44"50;
"RSVD<27>"
$PN"DT71"51;
"RSVD<28>"
$PN"DR44"52;
"RSVD<29>"
$PN"DP65"53;
"RSVD<30>"
$PN"DP17"54;
"RSVD<31>"
$PN"DN66"55;
"RSVD<32>"
$PN"DN62"56;
"RSVD<33>"
$PN"DM67"57;
"RSVD<34>"
$PN"DL66"58;
"RSVD<35>"
$PN"DL38"59;
"RSVD<36>"
$PN"DK67"60;
"RSVD<37>"
$PN"DK65"61;
"RSVD<38>"
$PN"DK37"62;
"RSVD<39>"
$PN"DK15"63;
"RSVD<40>"
$PN"DJ66"64;
"RSVD<41>"
$PN"DJ36"65;
"RSVD<42>"
$PN"DH65"66;
"RSVD<43>"
$PN"DG64"67;
"RSVD<44>"
$PN"DG36"68;
"RSVD<45>"
$PN"DD51"69;
"RSVD<46>"
$PN"DC52"70;
"RSVD<47>"
$PN"DC46"71;
"RSVD<48>"
$PN"DA56"72;
"RSVD<49>"
$PN"DA54"73;
"RSVD<50>"
$PN"DA52"74;
"RSVD<51>"
$PN"DA40"75;
"RSVD<52>"
$PN"DA24"1;
"RSVD<53>"
$PN"CY73"76;
"RSVD<54>"
$PN"CY63"77;
"RSVD<55>"
$PN"CY57"78;
"RSVD<56>"
$PN"CY53"79;
"RSVD<57>"
$PN"CY39"80;
"RSVD<58>"
$PN"CY25"1;
"RSVD<59>"
$PN"CY23"81;
"RSVD<60>"
$PN"CW62"82;
"RSVD<61>"
$PN"CW60"9;
"RSVD<62>"
$PN"CW24"3;
"RSVD<63>"
$PN"CW22"10;
"RSVD<64>"
$PN"CV69"11;
"RSVD<65>"
$PN"CV23"3;
"RSVD<66>"
$PN"CU60"12;
"RSVD<67>"
$PN"CU6"13;
"RSVD<68>"
$PN"CU24"3;
"RSVD<69>"
$PN"CT69"14;
"RSVD<70>"
$PN"CT5"15;
"RSVD<71>"
$PN"CT23"3;
"RSVD<72>"
$PN"CR60"16;
"RSVD<73>"
$PN"CP31"17;
"RSVD<74>"
$PN"CP23"3;
"RSVD<75>"
$PN"CN28"18;
"RSVD<76>"
$PN"CN24"2;
"RSVD<77>"
$PN"CN22"20;
"RSVD<78>"
$PN"CM25"2;
"RSVD<79>"
$PN"CM23"2;
"RSVD<80>"
$PN"CL26"2;
"CD_VSS_VCC_CORE_SENSE"
$PN"BL16"6;
"CD_VCC_CORE_SENSE"
$PN"BN16"5;
"CD_VCCP_SENSE<0>"
$PN"BU16"8;
"CD_VCCP_SENSE<1>"
$PN"BT17"7;
%"PVCCIO_CPU0"
"1","(-5650,4175)","0","mstr_symbols","I23";
;
HDL_POWER"PVCCIO_CPU0"
BODY_TYPE"PLUMBING"
CDS_LIB"mstr_symbols"
VOLTAGE"1.1V";
"G\NAC"4;
END.
